# SCM (Grand Teton) — schematic netlist excerpt (pin names and nets, part order shuffled) for the footprints in the layout excerpt that follows; sources: Cadence DE-HDL packaged netlist, KiCad conversion of 12092022_DA0F0TMDCD0_F0T_Management_Board_D_brd_V3_OCP.brd

R525  Q_RES  0 5% CHIP  pkg 0402LF  page 41 : A = P3V3_AUX ; B = VCCIO1
R298  Q_RES  4.7K 1% CHIP  pkg 0402LF  page 28 : A = P3V3_AUX ; B = SMB_DEBUG_AUX_LVC3_USB_R1_SCL

(kicad_pcb
	(version 20260206)
	(generator "pcbnew")
	(generator_version "10.0")
	(general
		(thickness 1.6)
		(legacy_teardrops no)
	)
	(paper "A4")
	(title_block
		(title "12092022_DA0F0TMDCD0_F0T_Management_Board_D_brd_V3_OCP.brd")
		(comment 1 "Grand Teton / footprints 797-798 of 1440")
	)
	(layers
		(0 "F.Cu" signal "TOP")
		(4 "In1.Cu" signal "GND")
		(6 "In2.Cu" signal "IN1")
		(8 "In3.Cu" signal "GND1")
		(10 "In4.Cu" signal "IN2")
		(12 "In5.Cu" signal "VCC")
		(14 "In6.Cu" signal "VCC1")
		(16 "In7.Cu" signal "IN3")
		(18 "In8.Cu" signal "GND2")
		(20 "In9.Cu" signal "IN4")
		(22 "In10.Cu" signal "GND3")
		(2 "B.Cu" signal "BOTTOM")
		(9 "F.Adhes" user "F.Adhesive")
		(11 "B.Adhes" user "B.Adhesive")
		(13 "F.Paste" user "Package Geometry/Pastemask Top")
		(15 "B.Paste" user "Package Geometry/Pastemask Bottom")
		(5 "F.SilkS" user "Ref Des/Silkscreen Top")
		(7 "B.SilkS" user "Ref Des/Silkscreen Bottom")
		(1 "F.Mask" user "Board Geometry/Soldermask Top")
		(3 "B.Mask" user "Board Geometry/Soldermask Bottom")
		(17 "Dwgs.User" user "User.Drawings")
		(19 "Cmts.User" user "User.Comments")
		(21 "Eco1.User" user "User.Eco1")
		(23 "Eco2.User" user "User.Eco2")
		(25 "Edge.Cuts" user "Board Geometry/Outline")
		(27 "Margin" user)
		(31 "F.CrtYd" user "Package Geometry/Place Bound Top")
		(29 "B.CrtYd" user "Package Geometry/Place Bound Bottom")
		(35 "F.Fab" user "Ref Des/Assembly Top")
		(33 "B.Fab" user "Ref Des/Assembly Bottom")
	)
	(footprint ""
		(layer "B.Cu")
		(at 17.78 -70.104 90)
		(property "Reference" "R298"
			(at 0 0 90)
			(layer "B.SilkS")
			(hide yes)
			(effects
				(font
					(size 1.27 1.27)
				)
				(justify mirror)
			)
		)
		(property "Value" ""
			(at 0 0 90)
			(layer "B.Fab")
			(effects
				(font
					(size 1.27 1.27)
				)
				(justify mirror)
			)
		)
		(duplicate_pad_numbers_are_jumpers no)
		(fp_line
			(start 0.7874 -0.4064)
			(end -0.7874 -0.4064)
			(stroke
				(width 0.1524)
				(type default)
			)
			(layer "B.SilkS")
		)
		(fp_line
			(start -0.7874 -0.4064)
			(end -0.7874 0.4064)
			(stroke
				(width 0.1524)
				(type default)
			)
			(layer "B.SilkS")
		)
		(fp_line
			(start 0.7874 0.4064)
			(end 0.7874 -0.4064)
			(stroke
				(width 0.1524)
				(type default)
			)
			(layer "B.SilkS")
		)
		(fp_line
			(start -0.7874 0.4064)
			(end 0.7874 0.4064)
			(stroke
				(width 0.1524)
				(type default)
			)
			(layer "B.SilkS")
		)
		(fp_line
			(start 0.67945 -0.305054)
			(end 0.12065 -0.305054)
			(stroke
				(width 0.1)
				(type default)
			)
			(layer "B.Fab")
		)
		(fp_line
			(start 0.12065 -0.305054)
			(end 0.12065 -0.2794)
			(stroke
				(width 0.1)
				(type default)
			)
			(layer "B.Fab")
		)
		(fp_line
			(start -0.12065 -0.3048)
			(end -0.67945 -0.3048)
			(stroke
				(width 0.1)
				(type default)
			)
			(layer "B.Fab")
		)
		(fp_line
			(start -0.67945 -0.3048)
			(end -0.67945 0.3048)
			(stroke
				(width 0.1)
				(type default)
			)
			(layer "B.Fab")
		)
		(fp_line
			(start 0.12065 -0.2794)
			(end -0.12065 -0.2794)
			(stroke
				(width 0.1)
				(type default)
			)
			(layer "B.Fab")
		)
		(fp_line
			(start -0.12065 -0.2794)
			(end -0.12065 -0.3048)
			(stroke
				(width 0.1)
				(type default)
			)
			(layer "B.Fab")
		)
		(fp_line
			(start 0.12065 0.2794)
			(end 0.12065 0.3048)
			(stroke
				(width 0.1)
				(type default)
			)
			(layer "B.Fab")
		)
		(fp_line
			(start -0.120396 0.2794)
			(end 0.12065 0.2794)
			(stroke
				(width 0.1)
				(type default)
			)
			(layer "B.Fab")
		)
		(fp_line
			(start 0.67945 0.3048)
			(end 0.67945 -0.305054)
			(stroke
				(width 0.1)
				(type default)
			)
			(layer "B.Fab")
		)
		(fp_line
			(start 0.12065 0.3048)
			(end 0.67945 0.3048)
			(stroke
				(width 0.1)
				(type default)
			)
			(layer "B.Fab")
		)
		(fp_line
			(start -0.120396 0.3048)
			(end -0.120396 0.2794)
			(stroke
				(width 0.1)
				(type default)
			)
			(layer "B.Fab")
		)
		(fp_line
			(start -0.67945 0.3048)
			(end -0.120396 0.3048)
			(stroke
				(width 0.1)
				(type default)
			)
			(layer "B.Fab")
		)
		(pad "1" smd circle
			(at 0.40005 0 270)
			(size 0 0)
			(layers "B.Cu" "B.Mask" "B.Paste")
			(net "P3V3_AUX")
		)
		(pad "2" smd circle
			(at -0.40005 0 270)
			(size 0 0)
			(layers "B.Cu" "B.Mask" "B.Paste")
			(net "SMB_DEBUG_AUX_LVC3_USB_R1_SCL")
		)
	)
	(footprint ""
		(layer "B.Cu")
		(at 17.526 -98.679 90)
		(property "Reference" "R525"
			(at 0 0 90)
			(layer "B.SilkS")
			(hide yes)
			(effects
				(font
					(size 1.27 1.27)
				)
				(justify mirror)
			)
		)
		(property "Value" ""
			(at 0 0 90)
			(layer "B.Fab")
			(effects
				(font
					(size 1.27 1.27)
				)
				(justify mirror)
			)
		)
		(duplicate_pad_numbers_are_jumpers no)
		(fp_line
			(start 0.7874 -0.4064)
			(end -0.7874 -0.4064)
			(stroke
				(width 0.1524)
				(type default)
			)
			(layer "B.SilkS")
		)
		(fp_line
			(start -0.7874 -0.4064)
			(end -0.7874 0.4064)
			(stroke
				(width 0.1524)
				(type default)
			)
			(layer "B.SilkS")
		)
		(fp_line
			(start 0.7874 0.4064)
			(end 0.7874 -0.4064)
			(stroke
				(width 0.1524)
				(type default)
			)
			(layer "B.SilkS")
		)
		(fp_line
			(start -0.7874 0.4064)
			(end 0.7874 0.4064)
			(stroke
				(width 0.1524)
				(type default)
			)
			(layer "B.SilkS")
		)
		(fp_line
			(start 0.67945 -0.305054)
			(end 0.12065 -0.305054)
			(stroke
				(width 0.1)
				(type default)
			)
			(layer "B.Fab")
		)
		(fp_line
			(start 0.12065 -0.305054)
			(end 0.12065 -0.2794)
			(stroke
				(width 0.1)
				(type default)
			)
			(layer "B.Fab")
		)
		(fp_line
			(start -0.12065 -0.3048)
			(end -0.67945 -0.3048)
			(stroke
				(width 0.1)
				(type default)
			)
			(layer "B.Fab")
		)
		(fp_line
			(start -0.67945 -0.3048)
			(end -0.67945 0.3048)
			(stroke
				(width 0.1)
				(type default)
			)
			(layer "B.Fab")
		)
		(fp_line
			(start 0.12065 -0.2794)
			(end -0.12065 -0.2794)
			(stroke
				(width 0.1)
				(type default)
			)
			(layer "B.Fab")
		)
		(fp_line
			(start -0.12065 -0.2794)
			(end -0.12065 -0.3048)
			(stroke
				(width 0.1)
				(type default)
			)
			(layer "B.Fab")
		)
		(fp_line
			(start 0.12065 0.2794)
			(end 0.12065 0.3048)
			(stroke
				(width 0.1)
				(type default)
			)
			(layer "B.Fab")
		)
		(fp_line
			(start -0.120396 0.2794)
			(end 0.12065 0.2794)
			(stroke
				(width 0.1)
				(type default)
			)
			(layer "B.Fab")
		)
		(fp_line
			(start 0.67945 0.3048)
			(end 0.67945 -0.305054)
			(stroke
				(width 0.1)
				(type default)
			)
			(layer "B.Fab")
		)
		(fp_line
			(start 0.12065 0.3048)
			(end 0.67945 0.3048)
			(stroke
				(width 0.1)
				(type default)
			)
			(layer "B.Fab")
		)
		(fp_line
			(start -0.120396 0.3048)
			(end -0.120396 0.2794)
			(stroke
				(width 0.1)
				(type default)
			)
			(layer "B.Fab")
		)
		(fp_line
			(start -0.67945 0.3048)
			(end -0.120396 0.3048)
			(stroke
				(width 0.1)
				(type default)
			)
			(layer "B.Fab")
		)
		(pad "1" smd circle
			(at 0.40005 0 270)
			(size 0 0)
			(layers "B.Cu" "B.Mask" "B.Paste")
			(net "P3V3_AUX")
		)
		(pad "2" smd circle
			(at -0.40005 0 270)
			(size 0 0)
			(layers "B.Cu" "B.Mask" "B.Paste")
			(net "VCCIO1")
		)
	)
)
